FILE_TYPE=LIBRARY_PARTS;
TIME=' Created/Modified on Wed Mar 14 15:42:44 2007' ;
primitive 'Q_CRYSTAL';
  pin
    '1':
      PIN_NUMBER='(1)';
      INPUT_LOAD='(-0.01,0.01)';
      OUTPUT_LOAD='(1.0,-1.0)';
      BIDIRECTIONAL='TRUE';
    '2':
      PIN_NUMBER='(2)';
      INPUT_LOAD='(-0.01,0.01)';
      OUTPUT_LOAD='(1.0,-1.0)';
      BIDIRECTIONAL='TRUE';
  end_pin;
  body
    CLASS='DISCRETE';
    PART_NAME='Q_CRYSTAL';
    PHYS_DES_PREFIX='Y';
  end_body;
end_primitive;
END.
